# Stackup_F0T_FIO_4L_1p6mm_IT-170GT_RTF_Rev0p1_20211105.xls — Information (pcb-stackup)
| Stackup Information : |  |  |  |
| Stackup Type |  |  | Single Material |
| Project Name |  |  | F0T |
| Board Class |  |  | FIO |
| Number of Layers |  |  | 4 |
| PCB Material |  |  | IT-170GT |
| Copper Foil |  |  | RTF (Roughness < 4um) |
| PCB Thickness (mm) |  |  | 1.6 |
| PCB Thickness (mil) |  |  | 63 |
| Aspect Ratio |  |  | 6.43 |
| Last Update |  |  | 44505 |
| Revision |  |  | 0.1 |
| Creator |  |  | Allen |
| Loss Requirement Table : |  |  |  |
| SDD21 @ Freq(GHz) |  |  |  |
| Requirement (db/inch) | Layer |  |  |
|  | Loss |  |  |
| Stackup History : |  |  |  |
| Date (yyyy/mm/dd) | Revision | Notes |  |
| 44503 | 0.1 | First release |  |
